FILE_TYPE = MULTI_PHYS_TABLE;

PART 'CONN8_HBB1081L200D8H'

{========================================================================================}
:VALUE                    | PART_TYPE | MATERIAL | PART_NUMBER    = STANDARD        | LIFECYCLE      | PART_NUMBER   | JEDEC_TYPE         | DESCRIPTION                             | MANUFTR | MANUF_PN           | RD_CMPLS_LVL | CMPLS_LVL | CLASS | DIP_SMD | FROM_PJ   | DATA                       | FP_ECN | EE_CHECK_LIST | CREATOR | CREATEDAY  | PSL | STATUS | ESD_CDM | ESD_HBM | ESD_MM | MSD  | PIN_LENGTH_LONG_PIN | PIN_LENGTH_SHORT_PIN ;
{========================================================================================}
 'CONN8_HBB1081-L200D-8H' | 'THLF'    | 'IO'     | 'DFHD08MS197'(!) = ''               | ''               | 'DFHD08MS197' |'HEADER1X8XA_H340'| 'CONN DIP HEADER 8P 1R MS(P2.54,H8.38)' | 'FOX'   | 'HBB1081-L200D-8H' | 'EP(V1)'     | 'EP(V1)'  | 'IO'  | 'DIP'   | 'S3S-IAN' | 'FOX_HBB1081-L200D-8H.pdf' | ''     | ''            | ''      | '20190819' | ''  | ''     | 'NA'    | 'NA'    | 'NA'   | 'NA' | '120 MILS'          | '120 MILS'          
 'CONN8_HBB1081-L200D-8H' | 'THLF'    | 'EMPTY'  | 'DFHD08MS197'(!) = ''               | ''               | 'DFHD08MS197' |'HEADER1X8XA_H340'| 'CONN DIP HEADER 8P 1R MS(P2.54,H8.38)' | 'FOX'   | 'HBB1081-L200D-8H' | 'EP(V1)'     | 'EP(V1)'  | 'IO'  | 'DIP'   | 'S3S-IAN' | 'FOX_HBB1081-L200D-8H.pdf' | ''     | ''            | ''      | '20190819' | ''  | ''     | 'NA'    | 'NA'    | 'NA'   | 'NA' | '120 MILS'          | '120 MILS'          

END_PART

END.

